5
5
4
4
3
3
2
2
1
1
D D
C C
B B
A A
FAN Control Board 
LED DRIVER 
PCA9551 
EEPROM 
24LC64T 
I2C_C 
4P20S CONN 
NCT7904D TACH X12 
PWM_EXP_1A 
PWM_EXP_1B 
PWM_EXP_2A 
PWM_EXP_2B 
PWM_OUT 
FAN 
X 6 
NCT7368S 
THERMHOT# 
FAN MONITOR 
CURRENT SHUNT 
HOT-SWAP 
ADM1276 
PAGE02:Power Map 
PAGE06:I2C_Devices 
PAGE01:Block diagram 
PAGE03:FAN MONITOR NCT7904D 
PAGE04:PWM Compare NCT7368S 
PAGE05:P3V3&LEDs 
PAGE07:PWR&SIGNAL CONN 
PAGE08:HOT_SWAP  ADM1276 
PAGE09:FAN_CONN 
PAGE10:12V_HOT_SWAP 
PAGE11:Screws 
PAGE12:BLANK 
Buffer 
TSLV07 
PAGE13:BLANK 
GATE 
OR 
PWM SIGNAL SOURCE 
DEFAULT: PATH#1 
RESERVE: PATH#2 
1 2
GATE 
GATE 
OR 
OR 
SELF_1A_HB 
SELF_1B_HB 
SELF_2A_HB 
SELF_2B_HB 
PAGE14:BLANK 
Title 
Size Document Number Rev 
Date: Sheet 
of 
Lightning_FCB 1
BLOCK_DIAGRAM 
C
1 13 Thursday, March 09, 2017 
Wiwynn 
H/W R&D Dept. II 
8F,90,Sec. 1,Hsin Tai Wu Rd, 
Hsichih, Taipei Hsien 221, Taiwan, R.O.C 
Title 
Size Document Number Rev 
Date: Sheet 
of 
Lightning_FCB 1
BLOCK_DIAGRAM 
C
1 13 Thursday, March 09, 2017 
Wiwynn 
H/W R&D Dept. II 
8F,90,Sec. 1,Hsin Tai Wu Rd, 
Hsichih, Taipei Hsien 221, Taiwan, R.O.C 
Title 
Size Document Number Rev 
Date: Sheet 
of 
Lightning_FCB 1
BLOCK_DIAGRAM 
C
1 13 Thursday, March 09, 2017 
Wiwynn 
H/W R&D Dept. II 
8F,90,Sec. 1,Hsin Tai Wu Rd, 
Hsichih, Taipei Hsien 221, Taiwan, R.O.C 



5
5
4
4
3
3
2
2
1
1
D D
C C
B B
A A
POWER MAP 
P12V_AUX 
BUS BAR 
    PU1 
ADM1276-3ACPZ 
    PU6 
TPS2490DGSR 
     PU7 
TPS2490DGSR 
DY=Dummy parts 
  =not populated 
562R2F- GP 
562 = 562 ohm, (2K2R means 2.2K ohm) 
2 = size 0402 
F = 1% tolerance 
GP= Green Part (RoHS) 
RC size code as below: 
1 = 0201 
2= 0402 
3= 0603 
5= 0805 
6= 1206 
R tolerance code as below: 
D=0.5% 
F= 1% 
J= 5% 
SCD1U10V2KX-5GP 
D1U = 0.1uF (2D2U means 2.2uF) 
10Voltage (6D3V means 6.3V) 
2 = size 0402, K tolerance 
K=tolerance 
[ C code as below:] 
G=2% 
J=5% 
K=10% 
M=20% 
X=temp characteristics 
[ C Series/Temp] 
N=NPO 
X=X7R/X5R 
Y=Y5V 
-5=different symbol/customer 
GP= Green Part (RoHS) 
  U4 
SY8021 
EEPROM 
P12V 
 POWER CONN 
 51952-220LF 
 POWER CONN 
 51952-220LF 
FAN CONN 
12V 
LED 
LED DRIVER 
FAN MONITOR 
PWM COMPARER 
P12VU P12VL 
Title 
Size Document Number Rev
Date: Sheet 
of 
Lightning_FCB 1
Power Map 
A3 
2 13Thursday, March 09, 2017 
Wiwynn 
H/W R&D Dept. II 
8F,90,Sec. 1,Hsin Tai Wu Rd, 
Hsichih, Taipei Hsien 221, Taiwan, R.O.C
Title 
Size Document Number Rev
Date: Sheet 
of 
Lightning_FCB 1
Power Map 
A3 
2 13Thursday, March 09, 2017 
Wiwynn 
H/W R&D Dept. II 
8F,90,Sec. 1,Hsin Tai Wu Rd, 
Hsichih, Taipei Hsien 221, Taiwan, R.O.C
Title 
Size Document Number Rev
Date: Sheet 
of 
Lightning_FCB 1
Power Map 
A3 
2 13Thursday, March 09, 2017 
Wiwynn 
H/W R&D Dept. II 
8F,90,Sec. 1,Hsin Tai Wu Rd, 
Hsichih, Taipei Hsien 221, Taiwan, R.O.C



5
5
4
4
3
3
2
2
1
1
D D
C C
B B
A A
Operating current: 10mA 
FAN CONTROLLER 
NCT7904_3VDD 
NCT7904_TMPALM 
NCT7904_CLKIN 
NCT7904_D1+ 
NCT7904_D1- 
NCT7904_D1+ 
NCT7904_D1- 
NCT7904_ADR 
I2C_C_SCL_NCT7904 
I2C_C_SDA_NCT7904 
NCT7904_CASEOPEN 
NCT7904_RESET 
OSC_TRI_S 
NCT7904_D2- 
NCT7904D_PWM1 
NCT7904D_PWM2 
NCT7904D_PWM3 
NCT7904D_PWM4 
NCT7904_PECI 
NCT7904_LED 
NCT7904_D2+ 
NCT7904_VSEN8 
NCT7904_VSEN7 
NCT7904_VSEN9 
NCT7904_VSEN10 
NCT7904_VSEN11 
NCT7904_VSEN12 
NCT7904_VSEN13 
NCT7904_VSEN14 
NCT7904_THERMTRIP 
NCT7904_PROCHOT 
NCT7904_3VSB 
NCT7904_GND 
NCT7904_D2+ 
NCT7904_D2- 
NCT7904_3VSB 
NCT7904_SMI 
NCT7904_CLK 
NCT7904_RSTOUT 
NCT7904_VSEN6 
NCT7904_VSEN1 
NCT7904_VREF 
NCT7904_VSEN7 
NCT7904_VSEN9 NCT7904_VSEN_P12V_AUX 
P3V3 
P3V3 
P3V3 
P3V3 
P3V3 
P12VL 
P12VU 
P12V_AUX 
FANIN_11 9
FANIN_12 9
FANIN_9 9
FANIN_10 9
FANIN_7 9
FANIN_6 9
FANIN_8 9
FANIN_5 9
FANIN_3 9
FANIN_4 9
I2C_C_SCL 6,7,8 
I2C_C_SDA 6,7,8 
FANIN_1 9
FANIN_2 9
TEMP_ALM# 8,10 
NCT7904D_PWM1 4
NCT7904D_PWM2 4
NCT7904D_PWM3 4
Title 
Size Document Number Rev 
Date: Sheet 
of 
Lightning_FCB 1
FAN MONITOR NCT7904D 
C
3 13 Thursday, March 09, 2017 
Wiwynn 
H/W R&D Dept. II 
8F,90,Sec. 1,Hsin Tai Wu Rd, 
Hsichih, Taipei Hsien 221, Taiwan, R.O.C 
Title 
Size Document Number Rev 
Date: Sheet 
of 
Lightning_FCB 1
FAN MONITOR NCT7904D 
C
3 13 Thursday, March 09, 2017 
Wiwynn 
H/W R&D Dept. II 
8F,90,Sec. 1,Hsin Tai Wu Rd, 
Hsichih, Taipei Hsien 221, Taiwan, R.O.C 
Title 
Size Document Number Rev 
Date: Sheet 
of 
Lightning_FCB 1
FAN MONITOR NCT7904D 
C
3 13 Thursday, March 09, 2017 
Wiwynn 
H/W R&D Dept. II 
8F,90,Sec. 1,Hsin Tai Wu Rd, 
Hsichih, Taipei Hsien 221, Taiwan, R.O.C 
R5 
0R2J-2-GP 
12
R3 
4K7R2F-GP 
1 2
TP17 TPAD32-GP 1
TP5 TPAD32-GP 
1
R6 0R2J-2-GP DY 1 2
Q1 PMBS3904-1-GP 
3
1
2
R51 
0R2J-2-GP 
1 2
R16 
110KR2F-L-GP 
1 2
R128 
10KR2F-2-GP 
1 2
TP11 TPAD32-GP 1
R10 
1MR2J-1-GP 
1 2
L1 
FCM1608CF-121T03-GP 
1 2
R35 
10KR2F-2-GP 
1 2
L2 
FCM1608CF-121T03-GP 
1 2
R7 0R2J-2-GP DY 1 2
R50 
0R2J-2-GP 
DY 
1 2
R4 0R2J-2-GP 1 2
R9 
100KR2J-1-GP 
DY 
1 2
OSC1 
OSC-33MHZ-7-GP 
TRI-S 1 VDD 4
GND 2 OUT 3
R1 
0R2J-2-GP 
1 2
C7 
SC2200P50V2KX-2GP 
1 2
TP12 
TPAD32-GP 1
TP6 
TPAD32-GP 
1
C1 
SC10U25V5KX-GP 
1 2
1
TP13 TPAD32-GP 1
R2 
0R2J-2-GP 
1 2
TP16 
TPAD32-GP 
1
C6 
SC4D7U6D3V2MX-GP-U 
1 2
R11 
100KR2J-1-GP 
1 2
TP1 
TPAD32-GP 
1
C5 
SCD1U16V2KX-3GP 
1 2
Q2 PMBS3904-1-GP 
3
1
2
R8 
0R5J-5-GP 
1 2
R12 
4K7R2F-GP 
1 2
U1 
NCT7904D-GP 
VREF 1
TR1/D1+/VSEN2 2
D1-/VSEN3 3
TR2/D2+/VSEN4 4
D2-/VSEN5 5
TR3/VSEN6 6
VSEN7 7
TR4/VSEN8 8
VSEN9 9
VSEN10 10 
VSEN11 11 
VSEN12 12 
VSEN13 13 
VSEN14 14 
3VDD 15 
3VSB 16 
GPIOF/SMI# 17 P1_PROCHOT# 18 
VTT/VSEN1 19 
PECI/GPIO16/SCL_TSI 20 
P1_THERMTRIP#/SDA_TSI 21 
CLKIN/14_318M_33M_48M 22 
S_SMB_CLK 23 S_SMB_DAT 24 
M_SMB_CLK/FANIN_11/LED_EVNT_IN 25 
M_SMB_DATA/FANIN_12/LED_OUT 26 
ADD0 27 
WDT_RSTOUT#/GPIOG/VSEN17 28 
FANIN_1 29 
PWM1 30 
FANIN_2 31 
PWM2 32 
FANIN_3 33 
PWM3/VSEN18 34 
FANIN_4 35 
PWM4/DCOUT/VSEN19 36 
FANIN_5/GPIO13 37 
GPIO14/FANIN_6 38 
GPIO15/FANIN_7 39 
FANIN_8/GPIOA 40 
VOLT_ALM#/FANIN_9/GPIOB 41 
FAN_ALM#/FANIN_10/GPIOC 42 
GND 43 
TEMP_ALM#/GPIOD 44 
BEEP/GPIOE/LED 45 
RESTIN# 46 
CASEOPEN# 47 
VBAT 48 
TP15 TPAD32-GP 1
TP10 TPAD32-GP 1
C4 
SCD1U16V2KX-3GP 
1 2
TP14 TPAD32-GP 1
R14 
110KR2F-L-GP 
1 2
C8 
SC2200P50V2KX-2GP 
1 2
C2 
SCD1U16V2KX-3GP 
1 2
C3 
SC10U25V5KX-GP 
1 2
R15 
10KR2F-2-GP 
1 2
R36 
110KR2F-L-GP 
1 2



5
5
4
4
3
3
2
2
1
1
D D
C C
B B
A A
PWM_EXP_1A 
PWM_EXP_1B 
PWM_EXP_2A 
NCT7368S_SEL 
PWM_OUT 
PWM_BUFFER_IN_FAN5_FAN6 
PWM_BUFFER_IN_FAN1_FAN2 
PWM_OUT 
PWM_BUFFER_IN_FAN3_FAN4 
THERMHOT# 
SEB_PEER_1A_1B_HB_OUT 
SEB_PEER_2A_2B_HB_OUT 
THERMHOT#_R 
P3V3 
P3V3 
P3V3 P3V3 
P3V3 
P3V3 
P3V3 
P3V3 
P3V3 
P3V3 
PWM_EXP_1A 7
PWM_EXP_1B 7
PWM_EXP_2A 7
PWM_EXP_2B 7
NCT7904D_PWM1 3
NCT7904D_PWM2 3
NCT7904D_PWM3 3
PWM_OUT_FAN6 9
PWM_OUT_FAN5 9
PWM_OUT_FAN4 9
PWM_OUT_FAN3 9
PWM_OUT_FAN2 9
PWM_OUT_FAN1 9
SEB_PEER_1A_HB 7
SEB_PEER_1B_HB 7
SEB_PEER_2B_HB 7
SEB_PEER_2A_HB 7
Title 
Size Document Number Rev 
Date: Sheet 
of 
Lightning_FCB 1
PWM Compare NCT7368S 
C
4 13 Thursday, March 09, 2017 
Wiwynn 
H/W R&D Dept. II 
8F,90,Sec. 1,Hsin Tai Wu Rd, 
Hsichih, Taipei Hsien 221, Taiwan, R.O.C 
Title 
Size Document Number Rev 
Date: Sheet 
of 
Lightning_FCB 1
PWM Compare NCT7368S 
C
4 13 Thursday, March 09, 2017 
Wiwynn 
H/W R&D Dept. II 
8F,90,Sec. 1,Hsin Tai Wu Rd, 
Hsichih, Taipei Hsien 221, Taiwan, R.O.C 
Title 
Size Document Number Rev 
Date: Sheet 
of 
Lightning_FCB 1
PWM Compare NCT7368S 
C
4 13 Thursday, March 09, 2017 
Wiwynn 
H/W R&D Dept. II 
8F,90,Sec. 1,Hsin Tai Wu Rd, 
Hsichih, Taipei Hsien 221, Taiwan, R.O.C 
R17 
100KR2F-L1-GP 
1 2
R130 
4K7R2F-GP 
1 2
C9 
SC1U16V3KX-5GP 
1 2
C16 
SCD1U50V3KX-GP 
1 2
R162 0R2J-2-GP DY 1 2
R116 
470R2F-GP 
1 2
R132 
4K7R2F-GP 
1 2
R22 
4K7R2F-GP 
DY 
1 2
R20 
4K7R2F-GP 
1 2
R131 
4K7R2F-GP 
1 2
R21 
100KR2F-L1-GP 
1 2
R164 
0R2J-2-GP 
12
R165 
0R2J-2-GP 
12
C52 
SCD1U50V3KX-GP 
1 2
R134 
4K7R2F-GP 
1 2
R49 
4K7R2F-GP 
DY 
1 2
R23 
4K7R2F-GP 
DY 
1 2
R163 0R2J-2-GP DY 1 2
R133 
4K7R2F-GP 
1 2
C53 
SC1U16V3KX-5GP 
1 2
U11 
74LVC1G32GW-1GP 
A2
B1
GND 3 Y 4
VCC 5
R18 
100KR2F-L1-GP 
1 2
R161 0R2J-2-GP DY 1 2
R24 
4K7R2F-GP 
DY 
1 2
R52 
4K7R2F-GP 
DY 
1 2
R183 
0R2J-2-GP 
12
C12 
SC1U16V3KX-5GP 
1 2
R135 
4K7R2F-GP 
1 2
R176 
0R2J-2-GP 
12
C11 
SCD1U50V3KX-GP 
1 2
R114 
470R2F-GP 
1 2
U10 
74LVC1G32GW-1GP 
A2
B1
GND 3 Y 4
VCC 5
U7 
TSLV07APWR-GP 
1A 1 1Y 2
2A 3 2Y 4
3A 5 3Y 6
GND 7
4Y 84A 9
5Y 10 5A 11 
6Y 12 6A 13 
VCC 14 
R19 
100KR2F-L1-GP 
1 2 C54 
SCD1U50V3KX-GP 
1 2
R166 
4K7R2F-GP 
DY 
1 2
U3 
74LVC1G32GW-1GP 
A2
B1
GND 3 Y 4
VCC 5
C55 
SC1U16V3KX-5GP 
1 2
R167 
4K7R2F-GP 
DY 
1 2
C10 
SCD1U50V3KX-GP 
1 2
C15 
SC1U16V3KX-5GP 
1 2
R118 
470R2F-GP 
1 2
R120 
470R2F-GP 
1 2
U2 
NCT7368S-GP 
VCC 1
PWMIN1 2
PWMIN2 3
PWMIN3 4 SEL 5THERMHOT# 6PWMOUT 7PWMIN4 8GND 9



5
5
4
4
3
3
2
2
1
1
D D
C C
B B
A A
LED_DR_LED5_K 
LED_DR_LED4_K 
LED_DR_LED0_K 
P3V3_FB 
P3V3_IN 
P3V3_BS_NET 
P3V3_LX_REV 
P3V3_LX_COPPER P3V3_LX 
P3V3_EN 
LED_DR_LED3_K 
LED_DR_LED1_K 
LED_DR_LED4_BLUE 
LED_DR_LED2_BLUE 
LED_DR_LED1_BLUE 
LED_DR_LED2_K 
LED_DR_LED3_BLUE 
LED_DR_LED5_BLUE 
LED_DR_LED0_BLUE 
LED_DR_LED0_B 
LED_DR_LED1_B 
LED_DR_LED2_B 
LED_DR_LED3_B 
LED_DR_LED4_B 
LED_DR_LED5_B 
P3V3 
P3V3 
P12V 
P3V3 
P3V3 
P3V3 
P3V3 P3V3 
P12V 
P12V 
P12V 
P12V 
P12V 
P12V 
LED_DR_LED5 6
LED_DR_LED4 6
LED_DR_LED3 6
LED_DR_LED2 6
LED_DR_LED1 6
LED_DR_LED0 6
Title 
Size Document Number Rev 
Date: Sheet 
of 
Lightning_FCB 1
P3V3&LEDs 
C
5 13 Thursday, March 09, 2017 
Wiwynn 
H/W R&D Dept. II 
8F,90,Sec. 1,Hsin Tai Wu Rd, 
Hsichih, Taipei Hsien 221, Taiwan, R.O.C 
Title 
Size Document Number Rev 
Date: Sheet 
of 
Lightning_FCB 1
P3V3&LEDs 
C
5 13 Thursday, March 09, 2017 
Wiwynn 
H/W R&D Dept. II 
8F,90,Sec. 1,Hsin Tai Wu Rd, 
Hsichih, Taipei Hsien 221, Taiwan, R.O.C 
Title 
Size Document Number Rev 
Date: Sheet 
of 
Lightning_FCB 1
P3V3&LEDs 
C
5 13 Thursday, March 09, 2017 
Wiwynn 
H/W R&D Dept. II 
8F,90,Sec. 1,Hsin Tai Wu Rd, 
Hsichih, Taipei Hsien 221, Taiwan, R.O.C 
Q8 
PMBS3904-1-GP 
3
1
2
R37 
33R2F-3-GP DY 
1 2
R122 
1K8R6J-GP 
1 2
R125 
1K8R6J-GP 
1 2
Q6 
PMBS3904-1-GP 
3
1
2
R111 
2KR2F-3-GP 
1 2
R127 
1K8R6J-GP 
1 2
PR53 
10KR3J-L1-GP 
1 2
PR54 
0R3J-0-U-GP 
1 2
Q4 
PMBS3904-1-GP 
3
1
2
R154 
0R0805-PAD-2-GP 
1 2
U4 
SY8201ABC-GP 
BS 1 GND 2
FB 3EN 4
IN 5 LX 6
R124 
1K8R6J-GP 
1 2
R31 
33R2F-3-GP DY 
1 2
PR52 
47KR3F-GP 
1 2
RED 
ANODE 
COMMON CATHODE 
BLUE 
ANODE 
LED5 
LED-RB-6-GP 1
2
3
R123 
1K8R6J-GP 
1 2
RED 
ANODE 
COMMON CATHODE 
BLUE 
ANODE 
LED3 
LED-RB-6-GP 1
2
3
R119 
2KR2F-3-GP 
1 2
PC40 
SC4D7U50V6KX-L2-GP 
1 2 PC43 
SC22U16V6MX-GP 
1 2
R33 
33R2F-3-GP DY 
1 2
R30 
0R2J-2-GP 
1 2
R25 
33R2F-3-GP DY 
1 2
R34 
0R2J-2-GP 
1 2
Q3 
PMBS3904-1-GP 
3
1
2
Q5 
PMBS3904-1-GP 
3
1
2
R113 
2KR2F-3-GP 
1 2
PC42 
SC22P50V3JN-DLGP 
1 2
R126 
1K8R6J-GP 
1 2
Q7 
PMBS3904-1-GP 
3
1
2
R117 
2KR2F-3-GP 
1 2
PR55 
100KR2F-L1-GP 
1 2
R26 
0R2J-2-GP 
1 2
R28 
0R2J-2-GP 
1 2
PR57 
0R0603-PAD-2-GP 
1 2
RED 
ANODE 
COMMON CATHODE 
BLUE 
ANODE 
LED2 
LED-RB-6-GP 1
2
3
R32 
0R2J-2-GP 
1 2
RED 
ANODE 
COMMON CATHODE 
BLUE 
ANODE 
LED6 
LED-RB-6-GP 1
2
3
RED 
ANODE 
COMMON CATHODE 
BLUE 
ANODE 
LED1 
LED-RB-6-GP 1
2
3
R38 
0R2J-2-GP 
1 2
R29 
33R2F-3-GP DY 
1 2
R27 
33R2F-3-GP DY 
1 2
RED 
ANODE 
COMMON CATHODE 
BLUE 
ANODE 
LED4 
LED-RB-6-GP 1
2
3
PC41 
SCD1U16V2KX-3GP 
1 2
R115 
2KR2F-3-GP 
1 2
PR56 
22K1R3F-GP 
1 2
PL7 
IND-22UH-169-GP 
1 2
R121 
2KR2F-3-GP 
1 2



5
5
4
4
3
3
2
2
1
1
D D
C C
B B
A A
FCB_EEPROM_A0 
FCB_EEPROM_A1 
FCB_EEPROM_A2 
I2C_C_SCL_EEPROM 
EEPROM_WP 
I2C_C_SDA_EEPROM 
I2C_C_SDA_LEDDRV 
I2C_C_SCL_LEDDRV 
LED_DRV_A0 
LED_DRV_A1 
LED_DRV_A2 
LED_DRV_RST 
LED_DR_LED6_RESERVE 
LED_DR_LED7_RESERVE 
P3V3 P3V3 
P3V3 
P3V3 
P3V3 
I2C_C_SCL 3,7,8 
I2C_C_SDA 3,7,8 
I2C_C_SDA 3,7,8 
I2C_C_SCL 3,7,8 
LED_DR_LED1 5
LED_DR_LED3 5
LED_DR_LED2 5
LED_DR_LED5 5
LED_DR_LED4 5
LED_DR_LED0 5
Title 
Size Document Number Rev 
Date: Sheet 
of 
Lightning_FCB 1
I2C_Devices 
C
6 13 Thursday, March 09, 2017 
Wiwynn 
H/W R&D Dept. II 
8F,90,Sec. 1,Hsin Tai Wu Rd, 
Hsichih, Taipei Hsien 221, Taiwan, R.O.C 
Title 
Size Document Number Rev 
Date: Sheet 
of 
Lightning_FCB 1
I2C_Devices 
C
6 13 Thursday, March 09, 2017 
Wiwynn 
H/W R&D Dept. II 
8F,90,Sec. 1,Hsin Tai Wu Rd, 
Hsichih, Taipei Hsien 221, Taiwan, R.O.C 
Title 
Size Document Number Rev 
Date: Sheet 
of 
Lightning_FCB 1
I2C_Devices 
C
6 13 Thursday, March 09, 2017 
Wiwynn 
H/W R&D Dept. II 
8F,90,Sec. 1,Hsin Tai Wu Rd, 
Hsichih, Taipei Hsien 221, Taiwan, R.O.C 
R157 
330R2J-3-GP 
1 2
R54 4K7R2J-2-GP 1 2
TP18 
TPAD32-GP 
1
R47 
0R2J-2-GP 
1 2
R129 
330R2J-3-GP 
1 2
R43 
4K7R2J-2-GP 
1 2
R55 4K7R2J-2-GP 1 2
R149 
330R2J-3-GP 
1 2
R45 
0R2J-2-GP 
1 2
R58 
330R2J-3-GP 
DY 1 2
R155 
330R2J-3-GP 
1 2
R56 4K7R2J-2-GP 1 2
R41 
4K7R2J-2-GP 
DY 
1 2
R156 
330R2J-3-GP 
1 2
R48 
4K7R2J-2-GP 
1 2
R40 
4K7R2J-2-GP 
DY 
1 2
TP26 TPAD32-GP 1
C13 
SC1U16V3KX-5GP 
1 2
R44 
4K7R2J-2-GP 
1 2
R59 
330R2J-3-GP 
DY 1 2
R148 
330R2J-3-GP 
1 2
R106 
0R2J-2-GP 
12
U6 
PCA9551PW-T-2GP-U 
A0 1
A1 2
A2 3
VSS 8
RESET# 13 
SCL 14 
SDA 15 
VDD 16 LED0 4
LED1 5
LED2 6
LED3 7
LED4 9
LED5 10 
LED6 11 
LED7 12 
C19 
SC1U16V3KX-5GP 
1 2
R39 
4K7R2J-2-GP 
1 2
R107 
0R2J-2-GP 
12
C14 
SCD1U50V3KX-GP 
1 2
U5 
24LC64T-I-GP 
A1 2
A2 3
A0 1
SDA 5VSS 4 SCL 6WP 7VCC 8
C20 
SCD1U50V3KX-GP 
1 2
R42 
4K7R2J-2-GP 
DY 
1 2
R46 
0R2J-2-GP 
1 2
TP19 TPAD32-GP 1



5
5
4
4
3
3
2
2
1
1
D D
C C
B B
A A
HARDWARE REVISION 
0 For normal storage 
1 For cold storage 
TRAY ID 
0 for Lower Tray 
1 for Upper Tray 
Lower Tray ID detection Upper Tray ID detection 
SEB_PEER_1B_HB 
FCB_HW_REVISION 
SELF_1B_HB 
UPPER_TRAY_ID 
PEER_TRAY PRESENT_UPPER 
SELF_TRAY_PRESENT_UPPER 
SELF_TRAY_PRESENT_LOWER 
P12VU_2490_EN_1 
FCB_HW_REVISION 
LOWER_TRAY_ID UPPER_TRAY_ID 
I2C_C_SDA_CONN_R 
I2C_C_SCL_CONN_R 
PWM_EXP_1B 
P12VU_2490_EN_2 
PWM_EXP_2B 
P12VL_2490_EN_1 
P12VL_2490_EN_2 
I2C_C_SDA_CONN_R 
SEB_PEER_2B_HB 
SELF_2B_HB 
FCB_HW_REVISION 
LOWER_TRAY_ID 
PEER_TRAY PRESENT_LOWER SELF_TRAY_PRESENT_UPPER 
SELF_TRAY_PRESENT_LOWER 
SEB_PEER_2A_HB 
I2C_C_SCL_CONN_R 
PWM_EXP_1A 
SEB_PEER_1A_HB 
SELF_1A_HB 
PWM_EXP_2A 
SELF_2A_HB 
SD_LATCH_RELEASE_L 
SD_LATCH_RELEASE_U 
I2C_C_SDA_CONN_R 
I2C_C_SCL_CONN_R 
P12VU 
P12V_AUX 
P3V3 
P3V3 P3V3 
P12VL 
P3V3 
TEMP_ALM#_REVERSE_R 8
SEB_PEER_2B_HB 4
PWM_EXP_1B 4
PWM_EXP_2B 4
SEB_PEER_1B_HB 4
P12VU_2490_EN_1 10 
P12VU_2490_EN_2 10 
P12VL_2490_EN_1 10 
P12VL_2490_EN_2 10 
PWM_EXP_1A 4
SEB_PEER_2A_HB 4
PWM_EXP_2A 4
SEB_PEER_1A_HB 4
TEMP_ALM#_REVERSE_R 8
D_LATCH_PRE# 10 
D_LATCH_PRE# 10 
I2C_C_SDA 3,6,8 
I2C_C_SCL 3,6,8 
Title 
Size Document Number Rev 
Date: Sheet 
of 
Lightning_FCB 1
CONN 
C
7 13 Thursday, March 09, 2017 
Wiwynn 
H/W R&D Dept. II 
8F,90,Sec. 1,Hsin Tai Wu Rd, 
Hsichih, Taipei Hsien 221, Taiwan, R.O.C 
Title 
Size Document Number Rev 
Date: Sheet 
of 
Lightning_FCB 1
CONN 
C
7 13 Thursday, March 09, 2017 
Wiwynn 
H/W R&D Dept. II 
8F,90,Sec. 1,Hsin Tai Wu Rd, 
Hsichih, Taipei Hsien 221, Taiwan, R.O.C 
Title 
Size Document Number Rev 
Date: Sheet 
of 
Lightning_FCB 1
CONN 
C
7 13 Thursday, March 09, 2017 
Wiwynn 
H/W R&D Dept. II 
8F,90,Sec. 1,Hsin Tai Wu Rd, 
Hsichih, Taipei Hsien 221, Taiwan, R.O.C 
TC7 
ST68U16VDM-1-GP 
1 2
R361 
100R2J-2-GP 
1 2
H10 
HOLE 
1
C57 
SC220P50V3JN-GP 
DY 
1 2
R172 
0R2J-2-GP 
12
C23 
SCD1U50V3KX-GP 
1 2
TC2 
ST68U16VDM-1-GP 
1 2
R63 
0R2J-2-GP 
12
CN8 
JWT-CON3-S11-GP 
1
2
3
TC3 
ST68U16VDM-1-GP 
1 2
R62 0R2J-2-GP 12
C26 
SC1U25V3KX-1-GP 
1 2
R362 
100R2J-2-GP 
DY 
1 2
TC1 
ST68U16VDM-1-GP 
1 2
PAD2 
PAD-1P-424137-1-OG-GP 
1
R358 
10KR2F-2-GP 
DY 
1 2
PAD1 
PAD-1P-424137-2-OG-GP 
1
CN10 
FCI-CONN52-4R-1-GP 
P1_1 
P1_2 P1_3 
P1_4 
P1_5 
P1_6 P1_7 
P1_8 
P2_1 
P2_2 P2_3 
P2_4 
P2_5 
P2_6 P2_7 
P2_8 
P3_1 
P3_2 P3_3 
P3_4 
P3_5 
P3_6 P3_7 
P3_8 
P4_1 
P4_2 P4_3 
P4_4 
P4_5 
P4_6 P4_7 
P4_8 
NP1 
NP2 
A1 
B1 C1 
D1 
A2 
B2 C2 
D2 
A3 
B3 C3 
D3 
A4 
B4 C4 
D4 
A5 
B5 
D5 
C5 
NP3 
NP4 
R150 
10R2F-L-GP 
1 2
C24 
SCD1U50V3KX-GP 
1 2
R185 0R2J-2-GP 
DY 
1 2
TC8 
ST15U25VDM-1-GP 
1 2
TC4 
ST15U25VDM-1-GP 
1 2
H9 
HOLE 
1
R151 
10R2F-L-GP 
1 2
R186 0R2J-2-GP 
DY 
1 2
R173 
0R2J-2-GP 
12
C25 
SCD1U50V3KX-GP 
1 2
R60 
4K7R2F-GP 
1 2
H11 
HOLE 
1
R357 
10KR2F-2-GP 
DY 
1 2
R174 0R2J-2-GP 1 2
R61 
4K7R2F-GP 
1 2
H12 
HOLE 
1
R359 
10KR2F-2-GP 
1 2
R184 0R2J-2-GP 1 2
R175 0R2J-2-GP 1 2
TC5 
ST68U16VDM-1-GP 
1 2
CN9 
FCI-CONN52-4R-1-GP 
P1_1 
P1_2 P1_3 
P1_4 
P1_5 
P1_6 P1_7 
P1_8 
P2_1 
P2_2 P2_3 
P2_4 
P2_5 
P2_6 P2_7 
P2_8 
P3_1 
P3_2 P3_3 
P3_4 
P3_5 
P3_6 P3_7 
P3_8 
P4_1 
P4_2 P4_3 
P4_4 
P4_5 
P4_6 P4_7 
P4_8 
NP1 
NP2 
A1 
B1 C1 
D1 
A2 
B2 C2 
D2 
A3 
B3 C3 
D3 
A4 
B4 C4 
D4 
A5 
B5 
D5 
C5 
NP3 
NP4 
C56 
SC220P50V3JN-GP 
DY 
1 2
R171 0R2J-2-GP 1 2
TC6 
ST68U16VDM-1-GP 
1 2
R360 
100R2J-2-GP 
1 2



5
5
4
4
3
3
2
2
1
1
D D
C C
B B
A A
Initial time= 4.3ms 
Pin2,Pin3 short 
(Default) 
Pin1,Pin2 short 
Jumper (JP1) 
Setting Mode Function 
OCP&OTP Latch 
OCP Latch and OTP auto re-try 
ADM1276_SS 
ADM1276_Iset 
ADM1276_VCAP 
ADM1276_SENSE+ 
ADM1276_GATE_DRV 
ADM1276_GATE_DRV1 
ADM1276_GATE_DRV2 
ADM1276_GATE_DRV3 
ADM1276_TIMER 
ADM1276_VCC 
ADM1276_SENSE- 
P12V_SENSE_TRACE 
ADM1276_ADR 
ADM1276_GATE_RSV 
ADM1276_GATE_RC 
ADM1276_VOUT 
ADM1276_PWRGD 
ADM1276_GPIO2 
ADM1276_OV 
ADM1276_OV 
ADM1276_UV 
ADM1276_UV 
ADM1276_GATE 
ADM1276_FLB 
ADM1276_UV ADM1276_LATCH# 
ADM1276_VCAP 
I2C_C_SDA_ADM1276 
I2C_C_SCL_ADM1276 
ADM1276_EN 
SENSE+_R1 
SENSE-_R1 
SENSE+_R2 
SENSE-_R2 
SENSE-_R3 
SENSE-_R4 
SENSE+_R4 
SENSE+_R3 
ADM1276_EN_NET 
ADM1276_LATCH_B 
TEMP_ALM#_REVERSE 
ADM1276_GATE_DRV0 
ADM1276_LATCH# 
OTP_RETRY_B 
OTP_RETRY_C OTP_RETRY_DIODE 
ADM1276_EN 
TEMP_ALM#_JP_1 
TEMP_ALM#_G 
TEMP_ALM#_JP_2 
OTP_RETRY_G 
P12V_AUX 
P12V_AUX 
P12V 
P12V 
P12V 
P3V3 
P3V3 
P12V_AUX 
P12V_AUX 
P12V_AUX 
P12V_AUX 
P12V_AUX 
P12V_AUX 
P3V3 
P3V3 
I2C_C_SCL 3,6,7 
I2C_C_SDA 3,6,7 
ADM1276_EN 10 
TEMP_ALM#_REVERSE_R 7
TEMP_ALM# 3,10 
Title 
Size Document Number Rev 
Date: Sheet 
of 
Lightning_FCB 1
HOT_SWAP ADM1276 
Custom 
8 13 Thursday, March 09, 2017 
Wiwynn 
H/W R&D Dept. II 
8F,90,Sec. 1,Hsin Tai Wu Rd, 
Hsichih, Taipei Hsien 221, Taiwan, R.O.C 
Title 
Size Document Number Rev 
Date: Sheet 
of 
Lightning_FCB 1
HOT_SWAP ADM1276 
Custom 
8 13 Thursday, March 09, 2017 
Wiwynn 
H/W R&D Dept. II 
8F,90,Sec. 1,Hsin Tai Wu Rd, 
Hsichih, Taipei Hsien 221, Taiwan, R.O.C 
Title 
Size Document Number Rev 
Date: Sheet 
of 
Lightning_FCB 1
HOT_SWAP ADM1276 
Custom 
8 13 Thursday, March 09, 2017 
Wiwynn 
H/W R&D Dept. II 
8F,90,Sec. 1,Hsin Tai Wu Rd, 
Hsichih, Taipei Hsien 221, Taiwan, R.O.C 
PQ14 
PMBS3904-1-GP 
3
1
2
PR4 
49K9R2F-L-GP 
1 2
TC11 
ST68U16VDM-1-GP 
1 2
PR15 
4K7R2J-2-GP 
1 2
R363 
5K1R2F-2-GP 
DY 
1 2
R366 
10KR2F-2-GP 
1 2
PR36 
4K02R2F-GP 
1 2
PQ4 
MMBT3906-3-GP C
B
E
PR30 
D0005RL1632F-GP-U 
1 2
3 4
PC8 
SC1U25V5KX-1GP 
DY 
1 2
PR49 
4K7R2J-2-GP 12
C58 
SCD1U25V2KX-GP 
1 2
PR41 
1KR2F-3-GP 
1 2
PU1 
ADM1276-3ACPZ-RL-GP 
ENABLE 8
GPO2/ALERT2# 9
PWRGD 12 
VOUT 14 
GND 15 
VCC 19 
VCAP 2
ISET 3SS 4
TIMER 5
FLB 13 
SDA 10 
GATE 16 
LATCH# 6
SCL 11 
ADR 7
SENSE- 17 SENSE+ 18 
OV 1
UV 20 
EP 21 
PR34 
51KR2F-L-GP 
1 2
TC12 
ST15U25VDM-1-GP 
1 2
S
S
S
G
D
PQ13 
PH0925CL-GP 
1
2
3
4
5
PR2 
10R2F-L-GP 
1 2
PR21 
10R2F-L-GP 
1 2
PR26 
10R2F-L-GP 
1 2
TP22 
TPAD32-GP 
1
PR25 
0R2J-2-GP DY 
12
PR43 
1K5R5J-GP 
1 2
PD2 
SMCJ15A-1-GP 
AK
PR58 
10KR2F-2-GP 
1 2
PR48 
5K1R2F-2-GP 
1 2
TC9 
ST68U16VDM-1-GP 
1 2
PR22 
10R2F-L-GP 
1 2
PR29 
D0005RL1632F-GP-U 
1 2
3 4
PR24 
10R2F-L-GP 
DY 1 2
PR7 
1KR2F-3-GP 
1 2
D19 
CH751H-40PT-1GP 
KA
PR11 
150KR2F-L-GP 
DY 
1 2
D18 
CH751H-40PT-1GP 
KA
TC10 
ST68U16VDM-1-GP 
1 2
PR27 
10R2F-L-GP 
1 2
PR14 
0R2J-2-GP 
1 2
PR1 
100KR2F-L1-GP 
1 2
PR35 
4K7R2J-2-GP 
DY 1 2
R364 
0R2J-2-GP 
1 2
PR5 
0R2J-2-GP 
DY 1 2
PR12 
0R2J-2-GP 
DY 
1 2
PR10 
0R0402-PAD-2-GP 
1 2
PR28 
10R2F-L-GP 
1 2
C261 
SC10U25V6KX-1GP 
DY 
1 2
R108 0R2J-2-GP 1 2
PR40 
54K9R2F-L-GP 
1 2
C255 
SCD1U25V3KX-LL-GP 
DY 
1 2
C259 
SC10U25V6KX-1GP 
1 2
PC6 
SCD022U50V3KX-2-GP 
1 2
PR17 
10R2F-L-GP 
DY 
1 2
S
S
S
G
D
PQ1 
PH0925CL-GP 
1
2
3
4
5
PR16 
1KR2F-3-GP 
1 2
R109 0R2J-2-GP 1 2
PR18 
10R2F-L-GP 
1 2
PC7 
SC1U25V5KX-1GP 
DY 
1 2
S
S
S
G
D
PQ2 
PH0925CL-GP 
1
2
3
4
5
R365 
10MR2J-L-GP 
1 2
PC3 
SCD01U25V2KX-3GP 
DY 1 2
PQ5 
PMBS3904-1-GP 
3
1
2
R367 
10KR2F-2-GP 
1 2
PR46 
51KR2F-L-GP 
1 2
PR37 
4K99R2F-L-GP 
1 2
PR23 
10R2F-L-GP 
1 2
PR32 
D0005RL1632F-GP-U 
DY 
1 2
3 4
PC1 
SC1U25V3KX-1-GP 
1 2
C260 
SC10U25V6KX-1GP 
DY 
1 2
C51 
SCD1U10V2KX-4-LL-GP 
1 2
PR8 
11KR2F-L-GP 
1 2
Q49 
2N7002-11-GP 
G
SD
PC9 
SC1U25V5KX-1GP 
1 2
PC4 
SC1U25V3KX-1-GP 
1 2
PR42 
10KR2F-2-GP 
DY 
1 2
PR20 
10R2F-L-GP 
1 2
PC2 
SC10U25V5KX-GP 
1 2
JP1 
PIN-CON3-S3-GP 
1
2
3
PR19 
10R2F-L-GP 
1 2
PR38 
1KR2F-3-GP 
1 2
PQ6 
PMBS3904-1-GP 
3
1
2
PR31 
D0005RL1632F-GP-U 
1 2
3 4
PR51 
10R2F-L-GP 
1 2
PR3 
51K1R2F-GP 
1 2
Q10 
2N7002DW-7F-GP 
1
2
34
5
6
PR33 
51KR2F-L-GP 
1 2
PR9 
0R2J-2-GP DY 1 2
PD1 
MM3Z15VT1G-GP 
DY 
AK
D14 
MBRS340T3G-GP 
AK
PC5 
SCD01U25V2KX-3GP 1 2
PR6 
100KR2F-L1-GP 
1 2
PR59 
4K7R2F-GP 
1 2
PC10 
SC1U25V5KX-1GP 
1 2
PR116 
0R2J-2-GP DY 
1 2
S
S
S
G
D
PQ3 
PH0925CL-GP 
1
2
3
4
5
PR39 
5K1R2F-2-GP 
1 2



5
5
4
4
3
3
2
2
1
1
D D
C C
B B
A A
FAN_TACH11 
FAN_TACH12 
FAN_TACH10 
FAN_TACH9 
FAN_TACH8 
FAN_TACH7 
FAN_TACH5 
FAN_TACH4 FAN_TACH3 FAN_TACH2 FAN_TACH1 
P12V_FAN6 
P12V_FAN4 
P12V_FAN3 
P12V_FAN2 P12V_FAN1 
P12V_FAN5 
PWM_OUT_FAN2_NET PWM_OUT_FAN1_NET 
PWM_OUT_FAN4_NET 
PWM_OUT_FAN6_NET 
PWM_OUT_FAN3_NET 
PWM_OUT_FAN5_NET 
FAN_TACH6 
P12V 
P12V 
P12V 
P12V 
P12V 
P12V 
P12V 
P12V 
P12V 
P12V 
P12V 
P12V 
P12V 
P12V 
P12V 
P12V 
P12V 
P12V 
P12V 
P12V 
P12V 
P12V 
P12V 
P12V 
FANIN_11 3
FANIN_12 3
FANIN_9 3
FANIN_10 3
FANIN_7 3
FANIN_8 3
FANIN_5 
FANIN_6 3
FANIN_3 3 FANIN_4 3FANIN_1 3 FANIN_2 3
PWM_OUT_FAN2 4
PWM_OUT_FAN6 4
PWM_OUT_FAN5 4
PWM_OUT_FAN4 4
PWM_OUT_FAN3 4
PWM_OUT_FAN1 4
Title 
Size Document Number Rev 
Date: Sheet 
of 
Lightning_FCB 1
FAN_CONN 
C
9 13 Thursday, March 09, 2017 
Wiwynn 
H/W R&D Dept. II 
8F,90,Sec. 1,Hsin Tai Wu Rd, 
Hsichih, Taipei Hsien 221, Taiwan, R.O.C 
Title 
Size Document Number Rev 
Date: Sheet 
of 
Lightning_FCB 1
FAN_CONN 
C
9 13 Thursday, March 09, 2017 
Wiwynn 
H/W R&D Dept. II 
8F,90,Sec. 1,Hsin Tai Wu Rd, 
Hsichih, Taipei Hsien 221, Taiwan, R.O.C 
Title 
Size Document Number Rev 
Date: Sheet 
of 
Lightning_FCB 1
FAN_CONN 
C
9 13 Thursday, March 09, 2017 
Wiwynn 
H/W R&D Dept. II 
8F,90,Sec. 1,Hsin Tai Wu Rd, 
Hsichih, Taipei Hsien 221, Taiwan, R.O.C 
R70 
27KR3F-GP 
1 2
F2 
FUSE-3A15V-GP 
DY 1 2
D8 
BAS16H-GP 
K A
C40 
SC1U25V3KX-1-GP 
1 2
C43 
SCD1U16V2KX-3GP 
DY 
1 2
CN3 
JWT-CON5-42-GP 
1
2
3
4
5
C41 
SCD1U50V3KX-GP 
1 2
F1 
FUSE-3A15V-GP 
DY 1 2
R69 
4K7R2F-GP 
1 2
C34 
SC1U25V3KX-1-GP 
1 2
R94 
4K7R2F-GP 
1 2 R67 
4K7R2F-GP 
1 2
R92 
4K7R2F-GP 
DY 
1 2
C45 
SCD1U16V2KX-3GP 
DY 
1 2
R86 
27KR3F-GP 
1 2
CN1 
JWT-CON5-42-GP 
1
2
3
4
5
R85 
27KR3F-GP 
1 2
R72 
27KR3F-GP 
1 2
R64 
4K7R2F-GP DY 
1 2
R84 
27KR3F-GP 
1 2
C35 
SCD1U16V2KX-3GP 
DY 
1 2
R83 
4K7R2F-GP 
1 2
C36 
SCD1U16V2KX-3GP 
DY 
1 2
R103 
10KR2F-2-GP 1 2
R136 
0R2J-2-GP 
1 2
D2 
BAS16H-GP 
K A
R177 
0R1206-PAD-1-GP 
1 2
R77 
10KR2F-2-GP 
1 2
R98 
27KR3F-GP 
1 2
D11 
BAS16H-GP 
K A
D5 
BAS16H-GP 
K A
D4 
BAS16H-GP 
K A
R96 
4K7R2F-GP 
DY 
1 2
CN2 
JWT-CON5-42-GP 
1
2
3
4
5
R91 
10KR2F-2-GP 
1 2
TC14 
ST15U25VDM-1-GP 
1 2
C50 
SC1U25V3KX-1-GP 
1 2
R138 
0R2J-2-GP 
1 2
C44 
SCD1U16V2KX-3GP 
DY 
1 2
D1 
BAS16H-GP 
K A
D7 
BAS16H-GP 
K A
D6 
BAS16H-GP 
K A
F6 
FUSE-3A15V-GP 
DY 1 2
R101 
27KR3F-GP 
1 2
C37 
SCD1U16V2KX-3GP 
DY 
1 2
F3 
FUSE-3A15V-GP 
DY 1 2
R95 
4K7R2F-GP 
1 2
R66 
4K7R2F-GP 
1 2
C29 
SCD1U16V2KX-3GP 
DY 
1 2
TC18 
ST15U25VDM-1-GP 
1 2
C47 
SCD1U50V3KX-GP 
1 2
R137 
0R2J-2-GP 
1 2
TC13 
ST15U25VDM-1-GP 
1 2
R68 
4K7R2F-GP 
1 2
D12 
BAS16H-GP 
K A
R104 
10KR2F-2-GP 
1 2
R82 
4K7R2F-GP 
1 2
D9 
BAS16H-GP 
K A
R80 
4K7R2F-GP 
1 2
F4 
FUSE-3A15V-GP 
DY 1 2
R81 
4K7R2F-GP 
1 2
R76 
10KR2F-2-GP 
1 2
R71 
27KR3F-GP 
1 2
TC15 
ST15U25VDM-1-GP 
1 2
R74 
10KR2F-2-GP 
1 2
C33 
SCD1U50V3KX-GP 
1 2
R182 
0R1206-PAD-1-GP 
1 2
R181 
0R1206-PAD-1-GP 
1 2
R180 
0R1206-PAD-1-GP 
1 2
R99 
27KR3F-GP 
1 2
C27 
SCD1U16V2KX-3GP 
DY 
1 2
R79 
4K7R2F-GP 
DY 
1 2
R179 
0R1206-PAD-1-GP 
1 2
R90 
10KR2F-2-GP 
1 2
C30 
SCD1U16V2KX-3GP 
DY 
1 2
C46 
SCD1U16V2KX-3GP 
DY 
1 2
R93 
4K7R2F-GP 
1 2
R73 
27KR3F-GP 
1 2
R88 
10KR2F-2-GP 
1 2
R78 
4K7R2F-GP 
DY 1 2
F5 
FUSE-3A15V-GP 
DY 1 2
C38 
SCD1U16V2KX-3GP 
DY 
1 2
R75 
10KR2F-2-GP 
1 2
R97 
4K7R2F-GP 
1 2
R89 
10KR2F-2-GP 
1 2
TC16 
ST15U25VDM-1-GP 
1 2
CN5 
JWT-CON5-42-GP 
1
2
3
4
5
C31 
SCD1U50V3KX-GP 
1 2
R140 
0R2J-2-GP 
1 2
R139 
0R2J-2-GP 
1 2
R178 
0R1206-PAD-1-GP 
1 2
C42 
SC1U25V3KX-1-GP 
1 2
R141 
0R2J-2-GP 
1 2
D10 
BAS16H-GP 
K A
R102 
10KR2F-2-GP 
1 2
CN6 
JWT-CON5-42-GP 
1
2
3
4
5
TC17 
ST15U25VDM-1-GP 
1 2
R105 
10KR2F-2-GP 
1 2
D3 
BAS16H-GP 
K A
R87 
27KR3F-GP 
1 2
C49 
SCD1U50V3KX-GP 
1 2
C32 
SC1U25V3KX-1-GP 
1 2
C28 
SCD1U16V2KX-3GP 
DY 
1 2
R100 
27KR3F-GP 
1 2
C48 
SC1U25V3KX-1-GP 
1 2
CN4 
JWT-CON5-42-GP 
1
2
3
4
5
C39 
SCD1U50V3KX-GP 
1 2
R65 
4K7R2F-GP 
DY 
1 2



5
5
4
4
3
3
2
2
1
1
D D
C C
B B
A A
P12VU_2490_SENSE 
P12VU_2490_PG 
P12VU_2490_TIMER 
P12VU_2490_VCC 
P12VU_2490_RC P12VL_2490_SENSE 
P12VL_2490_VREF 
P12VL_2490_TIMER 
P12VL_2490_VCC 
P12VL_2490_RC 
P12VU_2490_GATE_DRV 
P12VL_2490_GATE_DRV P12VL_2490_GATE 
P12VU_2490_GATE 
P12VL_2490_PG 
P12VU_2490_VREF 
P12VL_2490_PROG 
P12VU_2490_PROG 
P3V3_AUX_BJT_B 
TEMP_ALM#_IN 
D_LATCH_PRE# 
D_LATCH_CLR 
D_LATCH_Q# 
TEMP_ALM#_IN_D 
D_LATCH_Q 
P12VU_NET P12VL_NET 
P12VU_2490_GATE_DRV_2 
P12VL_2490_GATE_DRV_2 
P12VU_2490_EN_2 P12VL_2490_EN_2 
P12V 
P12VU P12V P12VL 
P3V3_AUX 
P12V_AUX 
P3V3_AUX 
P3V3_AUX 
P3V3_AUX 
P3V3_AUX 
P3V3_AUX 
P3V3_AUX 
P3V3_AUX 
P12V 
P12V 
TEMP_ALM# 3,8 
ADM1276_EN 8
P12VL_2490_EN_2 7
P12VU_2490_EN_2 7
P12VU_2490_EN_1 7
P12VL_2490_EN_1 7
D_LATCH_PRE# 7
Title 
Size Document Number Rev 
Date: Sheet 
of 
Lightning_FCB 1
HOT SWAP TPS2490 
C
10 13 Thursday, March 09, 2017 
Wiwynn 
H/W R&D Dept. II 
8F,90,Sec. 1,Hsin Tai Wu Rd, 
Hsichih, Taipei Hsien 221, Taiwan, R.O.C 
Title 
Size Document Number Rev 
Date: Sheet 
of 
Lightning_FCB 1
HOT SWAP TPS2490 
C
10 13 Thursday, March 09, 2017 
Wiwynn 
H/W R&D Dept. II 
8F,90,Sec. 1,Hsin Tai Wu Rd, 
Hsichih, Taipei Hsien 221, Taiwan, R.O.C 
Title 
Size Document Number Rev 
Date: Sheet 
of 
Lightning_FCB 1
HOT SWAP TPS2490 
C
10 13 Thursday, March 09, 2017 
Wiwynn 
H/W R&D Dept. II 
8F,90,Sec. 1,Hsin Tai Wu Rd, 
Hsichih, Taipei Hsien 221, Taiwan, R.O.C 
PR99 
100R2F-L1-GP-U 
1 2
PR95 
0R2J-2-GP 
12
PC97 
SC10U25V5KX-GP 
DY 1 2
PR105 
2K7R2F-GP 
1 2
PR115 
20KR2F-L-GP 
1 2
PR47 
4K7R2J-2-GP 
1 2
TP23 
TPAD32-GP 
1
PR100 
1MR3J-L-GP 
DY 
1 2
PR101 
100R2F-L1-GP-U 
1 2
PR107 
1KR2F-3-GP 
1 2
PQ9 
PMBS3904-1-GP 
3
1
2
PR118 
10R2F-L-GP 
1 2
C257 
SC1U25V3KX-1-GP 
1 2
TP24 
TPAD32-GP 
1
PR102 
10R2F-L-GP 
1 2
R261 
10KR2J-3-GP 
1 2
PC91 
SCD01U50V3KX-4GP 
1 2
PC87 
SC220P50V2KX-3GP 
12
PR108 
6K81R2F-1-GP 
1 2
PR96 
12
S
S
S
G
D
PQ11 
PH0925CL-GP 
1
2
3
4
5
D16 
MBRS340T3G-GP 
AK
C254 
SCD1U16V2KX-3GP 
1 2
PC90 
SCD1U25V2KX-GP 
1 2
PR62 
D002R2512F-GP 
1 2
PC94 
SC220P50V2KX-3GP 
1 2
PQ10 
PMBS3904-1-GP 
3
1
2
S
S
S
G
D
PQ7 
PH0925CL-GP 
1
2
3
4
5
PR111 
178KR2F-GP 
1 2
PC88 
SC220P50V2KX-3GP 
12
PC1262 
SC10U16V6KX-2GP 
1 2
PC95 
SC10U25V5KX-GP 
1 2
C253 
SC4D7U6D3V3KX-GP 
1 2
PR44 
1KR2F-3-GP 
DY 
1 2
PR60 
D002R2512F-GP 
1 2
U8A 
TSAHC74PWR-GP 
D2
CLK 3
Q 5
Q# 6
VCC 14 
PRE# 4
GND 7
CLR# 1
PR106 
1KR2F-3-GP 
1 2
S
S
S
G
D
PQ8 
PH0925CL-GP 
1
2
3
4
5
S
S
S
G
D
PQ12 
PH0925CL-GP 
1
2
3
4
5
R270 
0R2J-2-GP 
DY 
1 2
PR97 
0R2J-2-GP 
12
PR45 
10KR2F-2-GP 
1 2
PC98 
SCD1U50V3KX-GP 
DY 1 2
TP21 
TPAD32-GP 
1
PR117 
3K3R3F-GP 
1 2
PR109 
6K81R2F-1-GP 
1 2
PC92 
SCD01U50V3KX-4GP 
1 2
PR114 
20KR2F-L-GP 
1 2
PU7 
TPS2490DGSR-GP 
EN 1
VREF 2
PROG 3
TIMER 4
GND 5
PG 6
OUT 7
GATE 8
SENSE 9
VCC 10 PU6 
TPS2490DGSR-GP 
EN 1
VREF 2
PROG 3
TIMER 4
GND 5
PG 6
OUT 7
GATE 8
SENSE 9
VCC 10 
PR98 
1MR3J-L-GP 
DY 
1 2
U8B 
TSAHC74PWR-GP 
D12 
CLK 11 
Q 9
Q# 8
VCC 14 
PRE# 10 
GND 7
CLR# 13 
R260 
47KR2J-2-GP 
1 2
PR94 
0R2J-2-GP 
12
C258 
SC1U25V3KX-1-GP 
1 2
PC85 
SCD01U25V2KX-3GP 
1 2
PR63 
D002R2512F-GP 
1 2
D15 
MBRS340T3G-GP 
AK
C256 
SCD1U16V2KX-3GP 
1 2
PR103 
10R2F-L-GP 
1 2
PR104 
2K7R2F-GP 
1 2
PC89 
SCD1U25V2KX-GP 
1 2
D13 
BZG05C3V9-GP 
K A
PR61 
D002R2512F-GP 
1 2
PR119 
10R2F-L-GP 
1 2
PC93 
SC220P50V2KX-3GP 
1 2
PC86 
SCD01U25V2KX-3GP 
1 2
PR112 
6K81R2F-1-GP 
1 2
PR110 
178KR2F-GP 
1 2 PR113 
6K81R2F-1-GP 
1 2
PC96 
SCD1U50V3KX-GP 
1 2



5
5
4
4
3
3
2
2
1
1
D D
C C
B B
A A
Title 
Size Document Number Rev
Date: Sheet 
of 
Lightning_FCB 1
Screws 
A3 
11 13Thursday, March 09, 2017 
Wiwynn 
H/W R&D Dept. II 
8F,90,Sec. 1,Hsin Tai Wu Rd, 
Hsichih, Taipei Hsien 221, Taiwan, R.O.C
Title 
Size Document Number Rev
Date: Sheet 
of 
Lightning_FCB 1
Screws 
A3 
11 13Thursday, March 09, 2017 
Wiwynn 
H/W R&D Dept. II 
8F,90,Sec. 1,Hsin Tai Wu Rd, 
Hsichih, Taipei Hsien 221, Taiwan, R.O.C
Title 
Size Document Number Rev
Date: Sheet 
of 
Lightning_FCB 1
Screws 
A3 
11 13Thursday, March 09, 2017 
Wiwynn 
H/W R&D Dept. II 
8F,90,Sec. 1,Hsin Tai Wu Rd, 
Hsichih, Taipei Hsien 221, Taiwan, R.O.C
H8 
HOLE 
1
H5 
HOLE 
1
H2 
HOLE 
1
H7 
HOLE 
1
H13 
HOLE 
1
H4 
HOLE 
1
H6 
HOLE 
1
H1 
HOLE 
1
H3 
HOLE 
1



5
5
4
4
3
3
2
2
1
1
D D
C C
B B
A A
BLANK 
Title 
Size Document Number Rev 
Date: Sheet 
of 
Lightning_FCB 1
BLANK 
C
12 13 Thursday, March 09, 2017 
Wiwynn 
H/W R&D Dept. II 
8F,90,Sec. 1,Hsin Tai Wu Rd, 
Hsichih, Taipei Hsien 221, Taiwan, R.O.C 
Title 
Size Document Number Rev 
Date: Sheet 
of 
Lightning_FCB 1
BLANK 
C
12 13 Thursday, March 09, 2017 
Wiwynn 
H/W R&D Dept. II 
8F,90,Sec. 1,Hsin Tai Wu Rd, 
Hsichih, Taipei Hsien 221, Taiwan, R.O.C 
Title 
Size Document Number Rev 
Date: Sheet 
of 
Lightning_FCB 1
BLANK 
C
12 13 Thursday, March 09, 2017 
Wiwynn 
H/W R&D Dept. II 
8F,90,Sec. 1,Hsin Tai Wu Rd, 
Hsichih, Taipei Hsien 221, Taiwan, R.O.C 



5
5
4
4
3
3
2
2
1
1
D D
C C
B B
A A
BLANK 
Title 
Size Document Number Rev 
Date: Sheet 
of 
Lightning_FCB 1
BLANK 
C
13 13 Thursday, March 09, 2017 
Wiwynn 
H/W R&D Dept. II 
8F,90,Sec. 1,Hsin Tai Wu Rd, 
Hsichih, Taipei Hsien 221, Taiwan, R.O.C 
Title 
Size Document Number Rev 
Date: Sheet 
of 
Lightning_FCB 1
BLANK 
C
13 13 Thursday, March 09, 2017 
Wiwynn 
H/W R&D Dept. II 
8F,90,Sec. 1,Hsin Tai Wu Rd, 
Hsichih, Taipei Hsien 221, Taiwan, R.O.C 
Title 
Size Document Number Rev 
Date: Sheet 
of 
Lightning_FCB 1
BLANK 
C
13 13 Thursday, March 09, 2017 
Wiwynn 
H/W R&D Dept. II 
8F,90,Sec. 1,Hsin Tai Wu Rd, 
Hsichih, Taipei Hsien 221, Taiwan, R.O.C 



5
5
4
4
3
3
2
2
1
1
D D
C C
B B
A A
BLANK 
Title 
Size Document Number Rev 
Date: Sheet 
of 
Lightning_FCB 1
BLANK 
C
14 14 Thursday, March 09, 2017 
Wiwynn 
H/W R&D Dept. II 
8F,90,Sec. 1,Hsin Tai Wu Rd, 
Hsichih, Taipei Hsien 221, Taiwan, R.O.C 
Title 
Size Document Number Rev 
Date: Sheet 
of 
Lightning_FCB 1
BLANK 
C
14 14 Thursday, March 09, 2017 
Wiwynn 
H/W R&D Dept. II 
8F,90,Sec. 1,Hsin Tai Wu Rd, 
Hsichih, Taipei Hsien 221, Taiwan, R.O.C 
Title 
Size Document Number Rev 
Date: Sheet 
of 
Lightning_FCB 1
BLANK 
C
14 14 Thursday, March 09, 2017 
Wiwynn 
H/W R&D Dept. II 
8F,90,Sec. 1,Hsin Tai Wu Rd, 
Hsichih, Taipei Hsien 221, Taiwan, R.O.C 